(kicad_pcb
	(version 20260206)
	(generator "pcbnew")
	(generator_version "10.0")
	(general
		(thickness 1.6)
		(legacy_teardrops no)
	)
	(paper "A4")
	(title_block
		(title "Bryce Canyon_R.DPB_16317-1_OCP.brd")
		(comment 1 "Bryce Canyon / footprints 1831-1838 of 2099")
	)
	(layers
		(0 "F.Cu" signal "TOP")
		(4 "In1.Cu" signal "L2GND")
		(6 "In2.Cu" signal "L3")
		(8 "In3.Cu" signal "L4VCC")
		(10 "In4.Cu" signal "L5VCC")
		(12 "In5.Cu" signal "L6")
		(14 "In6.Cu" signal "L7GND")
		(2 "B.Cu" signal "BOTTOM")
		(9 "F.Adhes" user "F.Adhesive")
		(11 "B.Adhes" user "B.Adhesive")
		(13 "F.Paste" user "Package Geometry/Pastemask Top")
		(15 "B.Paste" user "Package Geometry/Pastemask Bottom")
		(5 "F.SilkS" user "Ref Des/Silkscreen Top")
		(7 "B.SilkS" user "Ref Des/Silkscreen Bottom")
		(1 "F.Mask" user "Board Geometry/Soldermask Top")
		(3 "B.Mask" user "Board Geometry/Soldermask Bottom")
		(17 "Dwgs.User" user "User.Drawings")
		(19 "Cmts.User" user "User.Comments")
		(21 "Eco1.User" user "User.Eco1")
		(23 "Eco2.User" user "User.Eco2")
		(25 "Edge.Cuts" user "Board Geometry/Outline")
		(27 "Margin" user)
		(31 "F.CrtYd" user "Package Geometry/Place Bound Top")
		(29 "B.CrtYd" user "Package Geometry/Place Bound Bottom")
		(35 "F.Fab" user "Ref Des/Assembly Top")
		(33 "B.Fab" user "Ref Des/Assembly Bottom")
	)
	(footprint ""
		(layer "F.Cu")
		(at 22.1742 -15.9512 -90)
		(property "Reference" "R633"
			(at 0 0 270)
			(layer "F.SilkS")
			(hide yes)
			(effects
				(font
					(size 1.27 1.27)
				)
			)
		)
		(property "Value" "0R2J-2-GP"
			(at 0.064008 -3.993896 270)
			(unlocked yes)
			(layer "F.Fab")
			(hide yes)
			(effects
				(font
					(size 1.016 1.016)
					(thickness 0.1524)
				)
			)
		)
		(property "Device Type" "R402H16"
			(at 0.064008 -5.517896 270)
			(unlocked yes)
			(layer "F.Fab")
			(hide yes)
			(effects
				(font
					(size 1.016 1.016)
					(thickness 0.1524)
				)
			)
		)
		(duplicate_pad_numbers_are_jumpers no)
		(fp_line
			(start -0.508 -0.9398)
			(end -0.508 0.9398)
			(stroke
				(width 0.1524)
				(type default)
			)
			(layer "F.SilkS")
		)
		(fp_line
			(start 0.508 -0.9398)
			(end -0.508 -0.9398)
			(stroke
				(width 0.1524)
				(type default)
			)
			(layer "F.SilkS")
		)
		(fp_rect
			(start -0.508 0.9398)
			(end 0.508 -0.9398)
			(stroke
				(width 0)
				(type default)
			)
			(fill no)
			(layer "F.CrtYd")
		)
		(fp_rect
			(start -0.508 0.9398)
			(end 0.508 -0.9398)
			(stroke
				(width 0)
				(type default)
			)
			(fill no)
			(layer "F.Fab")
		)
		(pad "1" smd custom
			(at 0 -0.4445 270)
			(size 0.1397 0.1397)
			(layers "F.Cu" "F.Mask" "F.Paste")
			(net "DRIVE_B_24_PWR")
			(options
				(clearance outline)
				(anchor circle)
			)
			(primitives
				(gr_poly
					(pts
						(arc
							(start -0.1778 -0.2794)
							(mid -0.249642 -0.249642)
							(end -0.2794 -0.1778)
						)
						(arc
							(start -0.2794 0.1778)
							(mid -0.249642 0.249642)
							(end -0.1778 0.2794)
						)
						(arc
							(start 0.1778 0.2794)
							(mid 0.249642 0.249642)
							(end 0.2794 0.1778)
						)
						(arc
							(start 0.2794 -0.1778)
							(mid 0.249642 -0.249642)
							(end 0.1778 -0.2794)
						)
					)
					(width 0)
					(fill yes)
				)
			)
		)
		(pad "2" smd custom
			(at 0 0.4445 270)
			(size 0.1397 0.1397)
			(layers "F.Cu" "F.Mask" "F.Paste")
			(net "SW_PWR_R_HDD24")
			(options
				(clearance outline)
				(anchor circle)
			)
			(primitives
				(gr_poly
					(pts
						(arc
							(start -0.1778 -0.2794)
							(mid -0.249642 -0.249642)
							(end -0.2794 -0.1778)
						)
						(arc
							(start -0.2794 0.1778)
							(mid -0.249642 0.249642)
							(end -0.1778 0.2794)
						)
						(arc
							(start 0.1778 0.2794)
							(mid 0.249642 0.249642)
							(end 0.2794 0.1778)
						)
						(arc
							(start 0.2794 -0.1778)
							(mid 0.249642 -0.249642)
							(end 0.1778 -0.2794)
						)
					)
					(width 0)
					(fill yes)
				)
			)
		)
	)
	(footprint ""
		(layer "F.Cu")
		(at 481.339652 -248.750074 -90)
		(property "Reference" "VIA24"
			(at 0 0 270)
			(layer "F.SilkS")
			(hide yes)
			(effects
				(font
					(size 1.27 1.27)
				)
			)
		)
		(property "Value" "100OHM-8L-2D36MM-L16-GP"
			(at -3.4036 -0.4572 270)
			(unlocked yes)
			(layer "F.Fab")
			(hide yes)
			(effects
				(font
					(size 1.016 1.016)
					(thickness 0.1524)
				)
			)
		)
		(property "Device Type" "VIA-PCIE-4P-427097"
			(at -3.4036 -1.9812 270)
			(unlocked yes)
			(layer "F.Fab")
			(hide yes)
			(effects
				(font
					(size 1.016 1.016)
					(thickness 0.1524)
				)
			)
		)
		(duplicate_pad_numbers_are_jumpers no)
		(fp_rect
			(start -2.1336 0.4826)
			(end 2.1336 -0.4826)
			(stroke
				(width 0)
				(type default)
			)
			(fill no)
			(layer "F.CrtYd")
		)
		(fp_rect
			(start -2.1336 0.4826)
			(end 2.1336 -0.4826)
			(stroke
				(width 0)
				(type default)
			)
			(fill no)
			(layer "F.Fab")
		)
		(pad "1" thru_hole circle
			(at -1.651 0 270)
			(size 0.508 0.508)
			(drill 0.254)
			(layers "*.Cu" "*.Mask")
			(remove_unused_layers no)
			(net "GND")
			(clearance 0.2286)
			(thermal_gap 0.2286)
		)
		(pad "2" thru_hole circle
			(at -0.635 0 270)
			(size 0.508 0.508)
			(drill 0.254)
			(layers "*.Cu" "*.Mask")
			(remove_unused_layers no)
			(net "PHY_DRV_B_TO_SCC_B_11_DP")
			(clearance 0.2286)
			(thermal_gap 0.2286)
		)
		(pad "3" thru_hole circle
			(at 0.635 0 270)
			(size 0.508 0.508)
			(drill 0.254)
			(layers "*.Cu" "*.Mask")
			(remove_unused_layers no)
			(net "PHY_DRV_B_TO_SCC_B_11_DN")
			(clearance 0.2286)
			(thermal_gap 0.2286)
		)
		(pad "4" thru_hole circle
			(at 1.651 0 270)
			(size 0.508 0.508)
			(drill 0.254)
			(layers "*.Cu" "*.Mask")
			(remove_unused_layers no)
			(net "GND")
			(clearance 0.2286)
			(thermal_gap 0.2286)
		)
	)
	(footprint ""
		(layer "F.Cu")
		(at 55.245 -148.209)
		(property "Reference" "R368"
			(at 0 0 0)
			(layer "F.SilkS")
			(hide yes)
			(effects
				(font
					(size 1.27 1.27)
				)
			)
		)
		(property "Value" "2R6F-GP"
			(at -0.0508 -4.8514 0)
			(unlocked yes)
			(layer "F.Fab")
			(hide yes)
			(effects
				(font
					(size 1.016 1.016)
					(thickness 0.1524)
				)
			)
		)
		(property "Device Type" "R1206H26"
			(at 0 -6.3754 0)
			(unlocked yes)
			(layer "F.Fab")
			(hide yes)
			(effects
				(font
					(size 1.016 1.016)
					(thickness 0.1524)
				)
			)
		)
		(duplicate_pad_numbers_are_jumpers no)
		(fp_line
			(start -1.016 -2.2352)
			(end 1.016 -2.2352)
			(stroke
				(width 0.1524)
				(type default)
			)
			(layer "F.SilkS")
		)
		(fp_line
			(start -1.016 2.2352)
			(end -1.016 -2.2352)
			(stroke
				(width 0.1524)
				(type default)
			)
			(layer "F.SilkS")
		)
		(fp_line
			(start 1.016 -2.2352)
			(end 1.016 2.2352)
			(stroke
				(width 0.1524)
				(type default)
			)
			(layer "F.SilkS")
		)
		(fp_line
			(start 1.016 2.2352)
			(end -1.016 2.2352)
			(stroke
				(width 0.1524)
				(type default)
			)
			(layer "F.SilkS")
		)
		(fp_rect
			(start -1.0922 2.3114)
			(end 1.0922 -2.3114)
			(stroke
				(width 0)
				(type default)
			)
			(fill no)
			(layer "F.CrtYd")
		)
		(fp_poly
			(pts
				(xy -1.0922 -2.3114) (xy 1.0922 -2.3114) (xy 1.0922 2.3114) (xy -1.0922 2.3114)
			)
			(stroke
				(width 0)
				(type default)
			)
			(fill no)
			(layer "F.Fab")
		)
		(pad "1" smd rect
			(at 0 -1.397)
			(size 1.651 1.27)
			(layers "F.Cu" "F.Mask" "F.Paste")
			(net "P5V_HDD13")
		)
		(pad "2" smd rect
			(at 0 1.397)
			(size 1.651 1.27)
			(layers "F.Cu" "F.Mask" "F.Paste")
			(net "5V_PRE_13")
		)
	)
	(footprint ""
		(layer "F.Cu")
		(at 243.0907 -355.4476 -90)
		(property "Reference" "R1035"
			(at 0 0 270)
			(layer "F.SilkS")
			(hide yes)
			(effects
				(font
					(size 1.27 1.27)
				)
			)
		)
		(property "Value" "10R2F-L-GP"
			(at 0.064008 -3.993896 270)
			(unlocked yes)
			(layer "F.Fab")
			(hide yes)
			(effects
				(font
					(size 1.016 1.016)
					(thickness 0.1524)
				)
			)
		)
		(property "Device Type" "R402H14"
			(at 0.064008 -5.517896 270)
			(unlocked yes)
			(layer "F.Fab")
			(hide yes)
			(effects
				(font
					(size 1.016 1.016)
					(thickness 0.1524)
				)
			)
		)
		(duplicate_pad_numbers_are_jumpers no)
		(fp_line
			(start -0.508 -0.9398)
			(end -0.508 0.9398)
			(stroke
				(width 0.1524)
				(type default)
			)
			(layer "F.SilkS")
		)
		(fp_line
			(start 0.508 -0.9398)
			(end -0.508 -0.9398)
			(stroke
				(width 0.1524)
				(type default)
			)
			(layer "F.SilkS")
		)
		(fp_rect
			(start -0.508 0.9398)
			(end 0.508 -0.9398)
			(stroke
				(width 0)
				(type default)
			)
			(fill no)
			(layer "F.CrtYd")
		)
		(fp_rect
			(start -0.508 0.9398)
			(end 0.508 -0.9398)
			(stroke
				(width 0)
				(type default)
			)
			(fill no)
			(layer "F.Fab")
		)
		(pad "1" smd custom
			(at 0 -0.4445 270)
			(size 0.1397 0.1397)
			(layers "F.Cu" "F.Mask" "F.Paste")
			(net "MB3_CM_SENSE_R1_P")
			(options
				(clearance outline)
				(anchor circle)
			)
			(primitives
				(gr_poly
					(pts
						(arc
							(start -0.1778 -0.2794)
							(mid -0.249642 -0.249642)
							(end -0.2794 -0.1778)
						)
						(arc
							(start -0.2794 0.1778)
							(mid -0.249642 0.249642)
							(end -0.1778 0.2794)
						)
						(arc
							(start 0.1778 0.2794)
							(mid 0.249642 0.249642)
							(end 0.2794 0.1778)
						)
						(arc
							(start 0.2794 -0.1778)
							(mid 0.249642 -0.249642)
							(end 0.1778 -0.2794)
						)
					)
					(width 0)
					(fill yes)
				)
			)
		)
		(pad "2" smd custom
			(at 0 0.4445 270)
			(size 0.1397 0.1397)
			(layers "F.Cu" "F.Mask" "F.Paste")
			(net "MB3_CM_SENSE_P")
			(options
				(clearance outline)
				(anchor circle)
			)
			(primitives
				(gr_poly
					(pts
						(arc
							(start -0.1778 -0.2794)
							(mid -0.249642 -0.249642)
							(end -0.2794 -0.1778)
						)
						(arc
							(start -0.2794 0.1778)
							(mid -0.249642 0.249642)
							(end -0.1778 0.2794)
						)
						(arc
							(start 0.1778 0.2794)
							(mid 0.249642 0.249642)
							(end 0.2794 0.1778)
						)
						(arc
							(start 0.2794 -0.1778)
							(mid 0.249642 -0.249642)
							(end 0.1778 -0.2794)
						)
					)
					(width 0)
					(fill yes)
				)
			)
		)
	)
	(footprint ""
		(layer "F.Cu")
		(at 111.379 -139.065 -90)
		(property "Reference" "C233"
			(at 0 0 270)
			(layer "F.SilkS")
			(hide yes)
			(effects
				(font
					(size 1.27 1.27)
				)
			)
		)
		(property "Value" "SCD033U25V2KX-GP"
			(at 1.1811 -2.7051 270)
			(unlocked yes)
			(layer "F.Fab")
			(hide yes)
			(effects
				(font
					(size 1.016 1.016)
					(thickness 0.1524)
				)
			)
		)
		(property "Device Type" "C402H22"
			(at 1.1811 -4.2291 270)
			(unlocked yes)
			(layer "F.Fab")
			(hide yes)
			(effects
				(font
					(size 1.016 1.016)
					(thickness 0.1524)
				)
			)
		)
		(duplicate_pad_numbers_are_jumpers no)
		(fp_rect
			(start -0.4318 0.9525)
			(end 0.4318 -0.9525)
			(stroke
				(width 0)
				(type default)
			)
			(fill no)
			(layer "F.CrtYd")
		)
		(fp_rect
			(start -0.4318 0.9525)
			(end 0.4318 -0.9525)
			(stroke
				(width 0)
				(type default)
			)
			(fill no)
			(layer "F.Fab")
		)
		(pad "1" smd custom
			(at 0 -0.4445 270)
			(size 0.1524 0.1524)
			(layers "F.Cu" "F.Mask" "F.Paste")
			(net "SW_HDD_P15")
			(options
				(clearance outline)
				(anchor circle)
			)
			(primitives
				(gr_poly
					(pts
						(arc
							(start 0.3048 -0.2032)
							(mid 0.275042 -0.275042)
							(end 0.2032 -0.3048)
						)
						(arc
							(start -0.2032 -0.3048)
							(mid -0.275042 -0.275042)
							(end -0.3048 -0.2032)
						)
						(arc
							(start -0.3048 0.2032)
							(mid -0.275042 0.275042)
							(end -0.2032 0.3048)
						)
						(arc
							(start 0.2032 0.3048)
							(mid 0.275042 0.275042)
							(end 0.3048 0.2032)
						)
					)
					(width 0)
					(fill yes)
				)
			)
		)
		(pad "2" smd custom
			(at 0 0.4445 270)
			(size 0.1524 0.1524)
			(layers "F.Cu" "F.Mask" "F.Paste")
			(net "GND")
			(options
				(clearance outline)
				(anchor circle)
			)
			(primitives
				(gr_poly
					(pts
						(arc
							(start 0.3048 -0.2032)
							(mid 0.275042 -0.275042)
							(end 0.2032 -0.3048)
						)
						(arc
							(start -0.2032 -0.3048)
							(mid -0.275042 -0.275042)
							(end -0.3048 -0.2032)
						)
						(arc
							(start -0.3048 0.2032)
							(mid -0.275042 0.275042)
							(end -0.2032 0.3048)
						)
						(arc
							(start 0.2032 0.3048)
							(mid 0.275042 0.275042)
							(end 0.3048 0.2032)
						)
					)
					(width 0)
					(fill yes)
				)
			)
		)
	)
	(footprint ""
		(layer "F.Cu")
		(at 166.57193 -362.691426 180)
		(property "Reference" "R1013"
			(at 0 0 180)
			(layer "F.SilkS")
			(hide yes)
			(effects
				(font
					(size 1.27 1.27)
				)
			)
		)
		(property "Value" "3K92R2F-GP"
			(at 0.064008 -3.993896 180)
			(unlocked yes)
			(layer "F.Fab")
			(hide yes)
			(effects
				(font
					(size 1.016 1.016)
					(thickness 0.1524)
				)
			)
		)
		(property "Device Type" "R402H16"
			(at 0.064008 -5.517896 180)
			(unlocked yes)
			(layer "F.Fab")
			(hide yes)
			(effects
				(font
					(size 1.016 1.016)
					(thickness 0.1524)
				)
			)
		)
		(duplicate_pad_numbers_are_jumpers no)
		(fp_line
			(start 0.508 -0.9398)
			(end -0.508 -0.9398)
			(stroke
				(width 0.1524)
				(type default)
			)
			(layer "F.SilkS")
		)
		(fp_line
			(start -0.508 -0.9398)
			(end -0.508 0.9398)
			(stroke
				(width 0.1524)
				(type default)
			)
			(layer "F.SilkS")
		)
		(fp_rect
			(start -0.508 0.9398)
			(end 0.508 -0.9398)
			(stroke
				(width 0)
				(type default)
			)
			(fill no)
			(layer "F.CrtYd")
		)
		(fp_rect
			(start -0.508 0.9398)
			(end 0.508 -0.9398)
			(stroke
				(width 0)
				(type default)
			)
			(fill no)
			(layer "F.Fab")
		)
		(pad "1" smd custom
			(at 0 -0.4445 180)
			(size 0.1397 0.1397)
			(layers "F.Cu" "F.Mask" "F.Paste")
			(net "MB0_CM_OV_R")
			(options
				(clearance outline)
				(anchor circle)
			)
			(primitives
				(gr_poly
					(pts
						(arc
							(start -0.1778 -0.2794)
							(mid -0.249642 -0.249642)
							(end -0.2794 -0.1778)
						)
						(arc
							(start -0.2794 0.1778)
							(mid -0.249642 0.249642)
							(end -0.1778 0.2794)
						)
						(arc
							(start 0.1778 0.2794)
							(mid 0.249642 0.249642)
							(end 0.2794 0.1778)
						)
						(arc
							(start 0.2794 -0.1778)
							(mid 0.249642 -0.249642)
							(end 0.1778 -0.2794)
						)
					)
					(width 0)
					(fill yes)
				)
			)
		)
		(pad "2" smd custom
			(at 0 0.4445 180)
			(size 0.1397 0.1397)
			(layers "F.Cu" "F.Mask" "F.Paste")
			(net "AGND_CURRENT_MON")
			(options
				(clearance outline)
				(anchor circle)
			)
			(primitives
				(gr_poly
					(pts
						(arc
							(start -0.1778 -0.2794)
							(mid -0.249642 -0.249642)
							(end -0.2794 -0.1778)
						)
						(arc
							(start -0.2794 0.1778)
							(mid -0.249642 0.249642)
							(end -0.1778 0.2794)
						)
						(arc
							(start 0.1778 0.2794)
							(mid 0.249642 0.249642)
							(end 0.2794 0.1778)
						)
						(arc
							(start 0.2794 -0.1778)
							(mid 0.249642 -0.249642)
							(end 0.1778 -0.2794)
						)
					)
					(width 0)
					(fill yes)
				)
			)
		)
	)
	(footprint ""
		(layer "F.Cu")
		(at 427.863 -13.589 180)
		(property "Reference" "R837"
			(at 0 0 180)
			(layer "F.SilkS")
			(hide yes)
			(effects
				(font
					(size 1.27 1.27)
				)
			)
		)
		(property "Value" "1KR2F-3-GP"
			(at 0.064008 -3.993896 180)
			(unlocked yes)
			(layer "F.Fab")
			(hide yes)
			(effects
				(font
					(size 1.016 1.016)
					(thickness 0.1524)
				)
			)
		)
		(property "Device Type" "R402H16"
			(at 0.064008 -5.517896 180)
			(unlocked yes)
			(layer "F.Fab")
			(hide yes)
			(effects
				(font
					(size 1.016 1.016)
					(thickness 0.1524)
				)
			)
		)
		(duplicate_pad_numbers_are_jumpers no)
		(fp_line
			(start 0.508 -0.9398)
			(end -0.508 -0.9398)
			(stroke
				(width 0.1524)
				(type default)
			)
			(layer "F.SilkS")
		)
		(fp_line
			(start -0.508 -0.9398)
			(end -0.508 0.9398)
			(stroke
				(width 0.1524)
				(type default)
			)
			(layer "F.SilkS")
		)
		(fp_rect
			(start -0.508 0.9398)
			(end 0.508 -0.9398)
			(stroke
				(width 0)
				(type default)
			)
			(fill no)
			(layer "F.CrtYd")
		)
		(fp_rect
			(start -0.508 0.9398)
			(end 0.508 -0.9398)
			(stroke
				(width 0)
				(type default)
			)
			(fill no)
			(layer "F.Fab")
		)
		(pad "1" smd custom
			(at 0 -0.4445 180)
			(size 0.1397 0.1397)
			(layers "F.Cu" "F.Mask" "F.Paste")
			(net "P3V3_STBY_B")
			(options
				(clearance outline)
				(anchor circle)
			)
			(primitives
				(gr_poly
					(pts
						(arc
							(start -0.1778 -0.2794)
							(mid -0.249642 -0.249642)
							(end -0.2794 -0.1778)
						)
						(arc
							(start -0.2794 0.1778)
							(mid -0.249642 0.249642)
							(end -0.1778 0.2794)
						)
						(arc
							(start 0.1778 0.2794)
							(mid 0.249642 0.249642)
							(end 0.2794 0.1778)
						)
						(arc
							(start 0.2794 -0.1778)
							(mid 0.249642 -0.249642)
							(end 0.1778 -0.2794)
						)
					)
					(width 0)
					(fill yes)
				)
			)
		)
		(pad "2" smd custom
			(at 0 0.4445 180)
			(size 0.1397 0.1397)
			(layers "F.Cu" "F.Mask" "F.Paste")
			(net "SW_PWR_R_HDD33")
			(options
				(clearance outline)
				(anchor circle)
			)
			(primitives
				(gr_poly
					(pts
						(arc
							(start -0.1778 -0.2794)
							(mid -0.249642 -0.249642)
							(end -0.2794 -0.1778)
						)
						(arc
							(start -0.2794 0.1778)
							(mid -0.249642 0.249642)
							(end -0.1778 0.2794)
						)
						(arc
							(start 0.1778 0.2794)
							(mid 0.249642 0.249642)
							(end 0.2794 0.1778)
						)
						(arc
							(start 0.2794 -0.1778)
							(mid 0.249642 -0.249642)
							(end 0.1778 -0.2794)
						)
					)
					(width 0)
					(fill yes)
				)
			)
		)
	)
	(footprint ""
		(layer "F.Cu")
		(at 80.01 -247.65 180)
		(property "Reference" "D2"
			(at 0 0 180)
			(layer "F.SilkS")
			(hide yes)
			(effects
				(font
					(size 1.27 1.27)
				)
			)
		)
		(property "Value" "RB551V30-GP"
			(at 0 -6.7818 180)
			(unlocked yes)
			(layer "F.Fab")
			(hide yes)
			(effects
				(font
					(size 1.016 1.016)
					(thickness 0.1524)
				)
			)
		)
		(property "Device Type" "SOD323AKH38"
			(at 0 -8.6868 180)
			(unlocked yes)
			(layer "F.Fab")
			(hide yes)
			(effects
				(font
					(size 1.016 1.016)
					(thickness 0.1524)
				)
			)
		)
		(duplicate_pad_numbers_are_jumpers no)
		(fp_line
			(start 0.889 2.159)
			(end -0.889 2.159)
			(stroke
				(width 0.1524)
				(type default)
			)
			(layer "F.SilkS")
		)
		(fp_line
			(start 0.889 -1.9304)
			(end 0.889 2.159)
			(stroke
				(width 0.1524)
				(type default)
			)
			(layer "F.SilkS")
		)
		(fp_line
			(start 0.762 2.0574)
			(end -0.762 2.0574)
			(stroke
				(width 0.508)
				(type default)
			)
			(layer "F.SilkS")
		)
		(fp_line
			(start -0.889 2.159)
			(end -0.889 -1.9304)
			(stroke
				(width 0.1524)
				(type default)
			)
			(layer "F.SilkS")
		)
		(fp_line
			(start -0.889 -1.9304)
			(end 0.889 -1.9304)
			(stroke
				(width 0.1524)
				(type default)
			)
			(layer "F.SilkS")
		)
		(fp_rect
			(start -1.016 2.3114)
			(end 1.016 -2.0066)
			(stroke
				(width 0)
				(type default)
			)
			(fill no)
			(layer "F.CrtYd")
		)
		(fp_poly
			(pts
				(xy -1.016 -2.0066) (xy 1.016 -2.0066) (xy 1.016 2.3114) (xy -1.016 2.3114)
			)
			(stroke
				(width 0)
				(type default)
			)
			(fill no)
			(layer "F.Fab")
		)
		(pad "A" smd rect
			(at 0 -1.143 180)
			(size 0.5588 1.016)
			(layers "F.Cu" "F.Mask" "F.Paste")
			(net "SW_HDD_R2")
		)
		(pad "K" smd rect
			(at 0 1.143 180)
			(size 0.5588 1.016)
			(layers "F.Cu" "F.Mask" "F.Paste")
			(net "SW_HDD_N2")
		)
	)
)
